(kicad_pcb
	(version 20260206)
	(generator "pcbnew")
	(generator_version "10.0")
	(general
		(thickness 1.6)
		(legacy_teardrops no)
	)
	(paper "A4")
	(title_block
		(title "04192023_DAF0TMB3IC0_F0TG_MB_C_brd_V02_OCP.brd")
		(comment 1 "Grand Teton / footprints 6997-7002 of 8354")
	)
	(layers
		(0 "F.Cu" signal "TOP")
		(4 "In1.Cu" signal "GND")
		(6 "In2.Cu" signal "IN1")
		(8 "In3.Cu" signal "GND1")
		(10 "In4.Cu" signal "IN2")
		(12 "In5.Cu" signal "GND2")
		(14 "In6.Cu" signal "IN3")
		(16 "In7.Cu" signal "GND3")
		(18 "In8.Cu" signal "VCC")
		(20 "In9.Cu" signal "VCC1")
		(22 "In10.Cu" signal "GND4")
		(24 "In11.Cu" signal "IN4")
		(26 "In12.Cu" signal "GND5")
		(28 "In13.Cu" signal "IN5")
		(30 "In14.Cu" signal "GND6")
		(32 "In15.Cu" signal "IN6")
		(34 "In16.Cu" signal "GND7")
		(2 "B.Cu" signal "BOTTOM")
		(9 "F.Adhes" user "F.Adhesive")
		(11 "B.Adhes" user "B.Adhesive")
		(13 "F.Paste" user "Package Geometry/Pastemask Top")
		(15 "B.Paste" user "Package Geometry/Pastemask Bottom")
		(5 "F.SilkS" user "Ref Des/Silkscreen Top")
		(7 "B.SilkS" user "Ref Des/Silkscreen Bottom")
		(1 "F.Mask" user "Board Geometry/Soldermask Top")
		(3 "B.Mask" user "Board Geometry/Soldermask Bottom")
		(17 "Dwgs.User" user "User.Drawings")
		(19 "Cmts.User" user "User.Comments")
		(21 "Eco1.User" user "User.Eco1")
		(23 "Eco2.User" user "User.Eco2")
		(25 "Edge.Cuts" user "Board Geometry/Outline")
		(27 "Margin" user)
		(31 "F.CrtYd" user "Package Geometry/Place Bound Top")
		(29 "B.CrtYd" user "Package Geometry/Place Bound Bottom")
		(35 "F.Fab" user "Ref Des/Assembly Top")
		(33 "B.Fab" user "Ref Des/Assembly Bottom")
	)
	(footprint ""
		(layer "B.Cu")
		(at 342.624664 -73.534778)
		(property "Reference" "Q85"
			(at 1.4224 -1.768348 0)
			(unlocked yes)
			(layer "B.SilkS")
			(effects
				(font
					(size 0.7874 0.5842)
					(thickness 0.1524)
				)
				(justify left mirror)
			)
		)
		(property "Value" ""
			(at 0 0 0)
			(layer "B.Fab")
			(effects
				(font
					(size 1.27 1.27)
				)
				(justify mirror)
			)
		)
		(duplicate_pad_numbers_are_jumpers no)
		(fp_line
			(start -1.332738 -1.100074)
			(end -1.332738 1.100074)
			(stroke
				(width 0.1524)
				(type default)
			)
			(layer "B.SilkS")
		)
		(fp_line
			(start -1.332738 1.100074)
			(end 1.332738 1.100074)
			(stroke
				(width 0.1524)
				(type default)
			)
			(layer "B.SilkS")
		)
		(fp_line
			(start -0.4826 -1.100074)
			(end -1.332738 -1.100074)
			(stroke
				(width 0.1524)
				(type default)
			)
			(layer "B.SilkS")
		)
		(fp_line
			(start 0 -0.541274)
			(end -0.4826 -1.100074)
			(stroke
				(width 0.1524)
				(type default)
			)
			(layer "B.SilkS")
		)
		(fp_line
			(start 0.4826 -1.100074)
			(end 0 -0.541274)
			(stroke
				(width 0.1524)
				(type default)
			)
			(layer "B.SilkS")
		)
		(fp_line
			(start 1.332738 -1.100074)
			(end 0.4826 -1.100074)
			(stroke
				(width 0.1524)
				(type default)
			)
			(layer "B.SilkS")
		)
		(fp_line
			(start 1.332738 1.100074)
			(end 1.332738 -1.100074)
			(stroke
				(width 0.1524)
				(type default)
			)
			(layer "B.SilkS")
		)
		(fp_poly
			(pts
				(xy 1.345692 -0.649986) (xy 2.047748 -1.001014) (xy 2.047748 -0.298958)
			)
			(stroke
				(width 0)
				(type default)
			)
			(fill yes)
			(layer "B.SilkS")
		)
		(fp_line
			(start -0.674878 -1.100074)
			(end -0.674878 1.100074)
			(stroke
				(width 0.1)
				(type default)
			)
			(layer "B.Fab")
		)
		(fp_line
			(start -0.674878 1.100074)
			(end 0.674878 1.100074)
			(stroke
				(width 0.1)
				(type default)
			)
			(layer "B.Fab")
		)
		(fp_line
			(start 0.674878 -1.100074)
			(end -0.674878 -1.100074)
			(stroke
				(width 0.1)
				(type default)
			)
			(layer "B.Fab")
		)
		(fp_line
			(start 0.674878 1.100074)
			(end 0.674878 -1.100074)
			(stroke
				(width 0.1)
				(type default)
			)
			(layer "B.Fab")
		)
		(fp_poly
			(pts
				(xy 2.2352 -0.298958) (xy 2.2352 -1.001014) (xy 1.533144 -0.649986)
			)
			(stroke
				(width 0)
				(type default)
			)
			(fill yes)
			(layer "B.Fab")
		)
		(pad "1" smd rect
			(at 0.94996 -0.649986 90)
			(size 0.4318 0.508)
			(layers "B.Cu" "B.Mask" "B.Paste")
			(net "GND")
		)
		(pad "2" smd rect
			(at 0.94996 0 90)
			(size 0.4318 0.508)
			(layers "B.Cu" "B.Mask" "B.Paste")
			(net "FM_LED_PWRGD_PVDDCR_CPU1_P1")
		)
		(pad "3" smd rect
			(at 0.94996 0.649986 90)
			(size 0.4318 0.508)
			(layers "B.Cu" "B.Mask" "B.Paste")
			(net "LED_PWRGD_PVDDIO_P1_D")
		)
		(pad "4" smd rect
			(at -0.94996 0.649986 90)
			(size 0.4318 0.508)
			(layers "B.Cu" "B.Mask" "B.Paste")
			(net "GND")
		)
		(pad "5" smd rect
			(at -0.94996 0 90)
			(size 0.4318 0.508)
			(layers "B.Cu" "B.Mask" "B.Paste")
			(net "FM_LED_PWRGD_PVDDIO_P1")
		)
		(pad "6" smd rect
			(at -0.94996 -0.649986 90)
			(size 0.4318 0.508)
			(layers "B.Cu" "B.Mask" "B.Paste")
			(net "LED_PWRGD_PVDDCR_CPU1_P1_D")
		)
	)
	(footprint ""
		(layer "B.Cu")
		(at 161.406332 -386.766562 90)
		(property "Reference" "C387"
			(at 0 0 90)
			(layer "B.SilkS")
			(hide yes)
			(effects
				(font
					(size 1.27 1.27)
				)
				(justify mirror)
			)
		)
		(property "Value" ""
			(at 0 0 90)
			(layer "B.Fab")
			(effects
				(font
					(size 1.27 1.27)
				)
				(justify mirror)
			)
		)
		(duplicate_pad_numbers_are_jumpers no)
		(fp_line
			(start 0.299974 -0.150114)
			(end -0.299974 -0.150114)
			(stroke
				(width 0.1)
				(type default)
			)
			(layer "B.Fab")
		)
		(fp_line
			(start -0.299974 -0.150114)
			(end -0.299974 0.150114)
			(stroke
				(width 0.1)
				(type default)
			)
			(layer "B.Fab")
		)
		(fp_line
			(start 0.299974 0.150114)
			(end 0.299974 -0.150114)
			(stroke
				(width 0.1)
				(type default)
			)
			(layer "B.Fab")
		)
		(fp_line
			(start -0.299974 0.150114)
			(end 0.299974 0.150114)
			(stroke
				(width 0.1)
				(type default)
			)
			(layer "B.Fab")
		)
		(pad "1" smd rect
			(at 0.2667 0 270)
			(size 0.3048 0.381)
			(layers "B.Cu" "B.Mask" "B.Paste")
			(net "P0V9_CPU1_RT2_2A")
		)
		(pad "2" smd rect
			(at -0.2667 0 270)
			(size 0.3048 0.381)
			(layers "B.Cu" "B.Mask" "B.Paste")
			(net "GND")
		)
	)
	(footprint ""
		(layer "B.Cu")
		(at 72.072754 -204.228192 180)
		(property "Reference" "R557"
			(at 0 0 0)
			(layer "B.SilkS")
			(hide yes)
			(effects
				(font
					(size 1.27 1.27)
				)
				(justify mirror)
			)
		)
		(property "Value" ""
			(at 0 0 0)
			(layer "B.Fab")
			(effects
				(font
					(size 1.27 1.27)
				)
				(justify mirror)
			)
		)
		(duplicate_pad_numbers_are_jumpers no)
		(fp_line
			(start 0.7874 0.4064)
			(end 0.7874 -0.4064)
			(stroke
				(width 0.1524)
				(type default)
			)
			(layer "B.SilkS")
		)
		(fp_line
			(start 0.7874 -0.4064)
			(end -0.7874 -0.4064)
			(stroke
				(width 0.1524)
				(type default)
			)
			(layer "B.SilkS")
		)
		(fp_line
			(start -0.7874 0.4064)
			(end 0.7874 0.4064)
			(stroke
				(width 0.1524)
				(type default)
			)
			(layer "B.SilkS")
		)
		(fp_line
			(start -0.7874 -0.4064)
			(end -0.7874 0.4064)
			(stroke
				(width 0.1524)
				(type default)
			)
			(layer "B.SilkS")
		)
		(fp_line
			(start 0.67945 0.3048)
			(end 0.67945 -0.305054)
			(stroke
				(width 0.1)
				(type default)
			)
			(layer "B.Fab")
		)
		(fp_line
			(start 0.67945 -0.305054)
			(end 0.12065 -0.305054)
			(stroke
				(width 0.1)
				(type default)
			)
			(layer "B.Fab")
		)
		(fp_line
			(start 0.12065 0.3048)
			(end 0.67945 0.3048)
			(stroke
				(width 0.1)
				(type default)
			)
			(layer "B.Fab")
		)
		(fp_line
			(start 0.12065 0.2794)
			(end 0.12065 0.3048)
			(stroke
				(width 0.1)
				(type default)
			)
			(layer "B.Fab")
		)
		(fp_line
			(start 0.12065 -0.2794)
			(end -0.12065 -0.2794)
			(stroke
				(width 0.1)
				(type default)
			)
			(layer "B.Fab")
		)
		(fp_line
			(start 0.12065 -0.305054)
			(end 0.12065 -0.2794)
			(stroke
				(width 0.1)
				(type default)
			)
			(layer "B.Fab")
		)
		(fp_line
			(start -0.120396 0.3048)
			(end -0.120396 0.2794)
			(stroke
				(width 0.1)
				(type default)
			)
			(layer "B.Fab")
		)
		(fp_line
			(start -0.120396 0.2794)
			(end 0.12065 0.2794)
			(stroke
				(width 0.1)
				(type default)
			)
			(layer "B.Fab")
		)
		(fp_line
			(start -0.12065 -0.2794)
			(end -0.12065 -0.3048)
			(stroke
				(width 0.1)
				(type default)
			)
			(layer "B.Fab")
		)
		(fp_line
			(start -0.12065 -0.3048)
			(end -0.67945 -0.3048)
			(stroke
				(width 0.1)
				(type default)
			)
			(layer "B.Fab")
		)
		(fp_line
			(start -0.67945 0.3048)
			(end -0.120396 0.3048)
			(stroke
				(width 0.1)
				(type default)
			)
			(layer "B.Fab")
		)
		(fp_line
			(start -0.67945 -0.3048)
			(end -0.67945 0.3048)
			(stroke
				(width 0.1)
				(type default)
			)
			(layer "B.Fab")
		)
		(pad "1" smd circle
			(at 0.40005 0)
			(size 0 0)
			(layers "B.Cu" "B.Mask" "B.Paste")
			(net "PVDD18_S5_P1")
		)
		(pad "2" smd circle
			(at -0.40005 0)
			(size 0 0)
			(layers "B.Cu" "B.Mask" "B.Paste")
			(net "PWRGD_CPU1_PWROK")
		)
	)
	(footprint ""
		(layer "B.Cu")
		(at 157.94609 -388.011162 -90)
		(property "Reference" "C378"
			(at 0 0 90)
			(layer "B.SilkS")
			(hide yes)
			(effects
				(font
					(size 1.27 1.27)
				)
				(justify mirror)
			)
		)
		(property "Value" ""
			(at 0 0 90)
			(layer "B.Fab")
			(effects
				(font
					(size 1.27 1.27)
				)
				(justify mirror)
			)
		)
		(duplicate_pad_numbers_are_jumpers no)
		(fp_line
			(start -0.299974 0.150114)
			(end 0.299974 0.150114)
			(stroke
				(width 0.1)
				(type default)
			)
			(layer "B.Fab")
		)
		(fp_line
			(start 0.299974 0.150114)
			(end 0.299974 -0.150114)
			(stroke
				(width 0.1)
				(type default)
			)
			(layer "B.Fab")
		)
		(fp_line
			(start -0.299974 -0.150114)
			(end -0.299974 0.150114)
			(stroke
				(width 0.1)
				(type default)
			)
			(layer "B.Fab")
		)
		(fp_line
			(start 0.299974 -0.150114)
			(end -0.299974 -0.150114)
			(stroke
				(width 0.1)
				(type default)
			)
			(layer "B.Fab")
		)
		(pad "1" smd rect
			(at 0.2667 0 90)
			(size 0.3048 0.381)
			(layers "B.Cu" "B.Mask" "B.Paste")
			(net "P1V8_CPU1_RT2_1A_1D")
		)
		(pad "2" smd rect
			(at -0.2667 0 90)
			(size 0.3048 0.381)
			(layers "B.Cu" "B.Mask" "B.Paste")
			(net "GND")
		)
	)
	(footprint ""
		(layer "B.Cu")
		(at 307.34127 -193.99631)
		(property "Reference" "C88"
			(at 0 0 0)
			(layer "B.SilkS")
			(hide yes)
			(effects
				(font
					(size 1.27 1.27)
				)
				(justify mirror)
			)
		)
		(property "Value" ""
			(at 0 0 0)
			(layer "B.Fab")
			(effects
				(font
					(size 1.27 1.27)
				)
				(justify mirror)
			)
		)
		(duplicate_pad_numbers_are_jumpers no)
		(fp_line
			(start -0.7874 -0.4064)
			(end -0.7874 0.4064)
			(stroke
				(width 0.1524)
				(type default)
			)
			(layer "B.SilkS")
		)
		(fp_line
			(start -0.7874 0.4064)
			(end 0.7874 0.4064)
			(stroke
				(width 0.1524)
				(type default)
			)
			(layer "B.SilkS")
		)
		(fp_line
			(start 0.7874 -0.4064)
			(end -0.7874 -0.4064)
			(stroke
				(width 0.1524)
				(type default)
			)
			(layer "B.SilkS")
		)
		(fp_line
			(start 0.7874 0.4064)
			(end 0.7874 -0.4064)
			(stroke
				(width 0.1524)
				(type default)
			)
			(layer "B.SilkS")
		)
		(fp_line
			(start -0.67945 -0.3048)
			(end -0.67945 0.3048)
			(stroke
				(width 0.1)
				(type default)
			)
			(layer "B.Fab")
		)
		(fp_line
			(start -0.67945 0.3048)
			(end -0.120396 0.3048)
			(stroke
				(width 0.1)
				(type default)
			)
			(layer "B.Fab")
		)
		(fp_line
			(start -0.12065 -0.3048)
			(end -0.67945 -0.3048)
			(stroke
				(width 0.1)
				(type default)
			)
			(layer "B.Fab")
		)
		(fp_line
			(start -0.12065 -0.2794)
			(end -0.12065 -0.3048)
			(stroke
				(width 0.1)
				(type default)
			)
			(layer "B.Fab")
		)
		(fp_line
			(start -0.120396 0.2794)
			(end 0.12065 0.2794)
			(stroke
				(width 0.1)
				(type default)
			)
			(layer "B.Fab")
		)
		(fp_line
			(start -0.120396 0.3048)
			(end -0.120396 0.2794)
			(stroke
				(width 0.1)
				(type default)
			)
			(layer "B.Fab")
		)
		(fp_line
			(start 0.12065 -0.305054)
			(end 0.12065 -0.2794)
			(stroke
				(width 0.1)
				(type default)
			)
			(layer "B.Fab")
		)
		(fp_line
			(start 0.12065 -0.2794)
			(end -0.12065 -0.2794)
			(stroke
				(width 0.1)
				(type default)
			)
			(layer "B.Fab")
		)
		(fp_line
			(start 0.12065 0.2794)
			(end 0.12065 0.3048)
			(stroke
				(width 0.1)
				(type default)
			)
			(layer "B.Fab")
		)
		(fp_line
			(start 0.12065 0.3048)
			(end 0.67945 0.3048)
			(stroke
				(width 0.1)
				(type default)
			)
			(layer "B.Fab")
		)
		(fp_line
			(start 0.67945 -0.305054)
			(end 0.12065 -0.305054)
			(stroke
				(width 0.1)
				(type default)
			)
			(layer "B.Fab")
		)
		(fp_line
			(start 0.67945 0.3048)
			(end 0.67945 -0.305054)
			(stroke
				(width 0.1)
				(type default)
			)
			(layer "B.Fab")
		)
		(pad "1" smd circle
			(at 0.40005 0 180)
			(size 0 0)
			(layers "B.Cu" "B.Mask" "B.Paste")
			(net "P3V3_AUX")
		)
		(pad "2" smd circle
			(at -0.40005 0 180)
			(size 0 0)
			(layers "B.Cu" "B.Mask" "B.Paste")
			(net "GND")
		)
	)
	(footprint ""
		(layer "B.Cu")
		(at 212.471508 -2.537206 180)
		(property "Reference" "J80"
			(at 4.56946 -1.086358 270)
			(unlocked yes)
			(layer "B.SilkS")
			(effects
				(font
					(size 0.7874 0.5842)
					(thickness 0.1524)
				)
				(justify left mirror)
			)
		)
		(property "Value" ""
			(at 0 0 0)
			(layer "B.Fab")
			(effects
				(font
					(size 1.27 1.27)
				)
				(justify mirror)
			)
		)
		(duplicate_pad_numbers_are_jumpers no)
		(fp_line
			(start 1.2192 2.06756)
			(end 1.2192 -2.06756)
			(stroke
				(width 0.1524)
				(type default)
			)
			(layer "B.SilkS")
		)
		(fp_line
			(start 1.2192 -2.06756)
			(end -1.2192 -2.06756)
			(stroke
				(width 0.1524)
				(type default)
			)
			(layer "B.SilkS")
		)
		(fp_line
			(start -1.2192 2.06756)
			(end 1.2192 2.06756)
			(stroke
				(width 0.1524)
				(type default)
			)
			(layer "B.SilkS")
		)
		(fp_line
			(start -1.2192 -2.06756)
			(end -1.2192 2.06756)
			(stroke
				(width 0.1524)
				(type default)
			)
			(layer "B.SilkS")
		)
		(pad "" np_thru_hole circle
			(at -3.4671 -1.27 90)
			(size 1.0414 1.0414)
			(drill 1.0414)
			(layers "*.Cu" "*.Mask")
			(clearance 0.381)
			(thermal_gap 0.381)
		)
		(pad "" np_thru_hole circle
			(at -3.4671 1.27 90)
			(size 1.0414 1.0414)
			(drill 1.0414)
			(layers "*.Cu" "*.Mask")
			(clearance 0.381)
			(thermal_gap 0.381)
		)
		(pad "" np_thru_hole circle
			(at 2.8829 -1.27 90)
			(size 1.0414 1.0414)
			(drill 1.0414)
			(layers "*.Cu" "*.Mask")
			(clearance 0.381)
			(thermal_gap 0.381)
		)
		(pad "" np_thru_hole circle
			(at 2.8829 1.27 90)
			(size 1.0414 1.0414)
			(drill 1.0414)
			(layers "*.Cu" "*.Mask")
			(clearance 0.381)
			(thermal_gap 0.381)
		)
		(pad "1" smd rect
			(at -0.8255 -0.249936 90)
			(size 0.3048 0.508)
			(layers "B.Cu" "B.Mask" "B.Paste")
			(net "DELTA_L_85_10INCH_IN4_DP")
		)
		(pad "2" smd rect
			(at -0.8255 0.249936 90)
			(size 0.3048 0.508)
			(layers "B.Cu" "B.Mask" "B.Paste")
			(net "DELTA_L_85_10INCH_IN4_DN")
		)
		(pad "3" smd circle
			(at 0 0)
			(size 0 0)
			(layers "B.Cu" "B.Mask" "B.Paste")
			(net "DELTA_L_GND_1")
		)
		(zone
			(layers "F.Cu" "B.Cu" "In1.Cu" "In2.Cu" "In3.Cu" "In4.Cu" "In5.Cu" "In6.Cu"
				"In7.Cu" "In8.Cu" "In9.Cu" "In10.Cu" "In11.Cu" "In12.Cu" "In13.Cu" "In14.Cu"
				"In15.Cu" "In16.Cu"
			)
			(hatch none 0.5)
			(connect_pads
				(clearance 0)
			)
			(min_thickness 0.25)
			(keepout
				(tracks not_allowed)
				(vias allowed)
				(pads allowed)
				(copperpour not_allowed)
				(footprints allowed)
			)
			(placement
				(enabled no)
				(sheetname "")
			)
			(fill
				(thermal_gap 0.5)
				(thermal_bridge_width 0.5)
				(island_removal_mode 0)
			)
			(polygon
				(pts
					(arc
						(start 210.515708 -3.807206)
						(mid 208.661508 -3.807206)
						(end 210.515708 -3.807206)
					)
				)
			)
		)
		(zone
			(layers "F.Cu" "B.Cu" "In1.Cu" "In2.Cu" "In3.Cu" "In4.Cu" "In5.Cu" "In6.Cu"
				"In7.Cu" "In8.Cu" "In9.Cu" "In10.Cu" "In11.Cu" "In12.Cu" "In13.Cu" "In14.Cu"
				"In15.Cu" "In16.Cu"
			)
			(hatch none 0.5)
			(connect_pads
				(clearance 0)
			)
			(min_thickness 0.25)
			(keepout
				(tracks not_allowed)
				(vias allowed)
				(pads allowed)
				(copperpour not_allowed)
				(footprints allowed)
			)
			(placement
				(enabled no)
				(sheetname "")
			)
			(fill
				(thermal_gap 0.5)
				(thermal_bridge_width 0.5)
				(island_removal_mode 0)
			)
			(polygon
				(pts
					(arc
						(start 210.515708 -1.267206)
						(mid 208.661508 -1.267206)
						(end 210.515708 -1.267206)
					)
				)
			)
		)
		(zone
			(layers "F.Cu" "B.Cu" "In1.Cu" "In2.Cu" "In3.Cu" "In4.Cu" "In5.Cu" "In6.Cu"
				"In7.Cu" "In8.Cu" "In9.Cu" "In10.Cu" "In11.Cu" "In12.Cu" "In13.Cu" "In14.Cu"
				"In15.Cu" "In16.Cu"
			)
			(hatch none 0.5)
			(connect_pads
				(clearance 0)
			)
			(min_thickness 0.25)
			(keepout
				(tracks not_allowed)
				(vias allowed)
				(pads allowed)
				(copperpour not_allowed)
				(footprints allowed)
			)
			(placement
				(enabled no)
				(sheetname "")
			)
			(fill
				(thermal_gap 0.5)
				(thermal_bridge_width 0.5)
				(island_removal_mode 0)
			)
			(polygon
				(pts
					(arc
						(start 216.865708 -3.807206)
						(mid 215.011508 -3.807206)
						(end 216.865708 -3.807206)
					)
				)
			)
		)
		(zone
			(layers "F.Cu" "B.Cu" "In1.Cu" "In2.Cu" "In3.Cu" "In4.Cu" "In5.Cu" "In6.Cu"
				"In7.Cu" "In8.Cu" "In9.Cu" "In10.Cu" "In11.Cu" "In12.Cu" "In13.Cu" "In14.Cu"
				"In15.Cu" "In16.Cu"
			)
			(hatch none 0.5)
			(connect_pads
				(clearance 0)
			)
			(min_thickness 0.25)
			(keepout
				(tracks not_allowed)
				(vias allowed)
				(pads allowed)
				(copperpour not_allowed)
				(footprints allowed)
			)
			(placement
				(enabled no)
				(sheetname "")
			)
			(fill
				(thermal_gap 0.5)
				(thermal_bridge_width 0.5)
				(island_removal_mode 0)
			)
			(polygon
				(pts
					(arc
						(start 216.865708 -1.267206)
						(mid 215.011508 -1.267206)
						(end 216.865708 -1.267206)
					)
				)
			)
		)
		(zone
			(layer "B.Cu")
			(hatch none 0.5)
			(connect_pads
				(clearance 0)
			)
			(min_thickness 0.25)
			(keepout
				(tracks not_allowed)
				(vias allowed)
				(pads allowed)
				(copperpour not_allowed)
				(footprints allowed)
			)
			(placement
				(enabled no)
				(sheetname "")
			)
			(fill
				(thermal_gap 0.5)
				(thermal_bridge_width 0.5)
				(island_removal_mode 0)
			)
			(polygon
				(pts
					(xy 213.589108 -1.988566) (xy 213.589108 -2.08407) (xy 212.992208 -2.08407) (xy 212.992208 -2.49047)
					(xy 213.589108 -2.49047) (xy 213.589108 -2.583942) (xy 212.992208 -2.583942) (xy 212.992208 -2.990342)
					(xy 213.589108 -2.990342) (xy 213.589108 -3.085846) (xy 212.890608 -3.085846) (xy 212.890608 -1.988566)
				)
			)
		)
	)
)
